(kicad_pcb
	(version 20260206)
	(generator "pcbnew")
	(generator_version "10.0")
	(general
		(thickness 1.6)
		(legacy_teardrops no)
	)
	(paper "A4")
	(title_block
		(title "04192023_DAF0TMB3IC0_F0TG_MB_C_brd_V02_OCP.brd")
		(comment 1 "Grand Teton / footprints 8037-8043 of 8354")
	)
	(layers
		(0 "F.Cu" signal "TOP")
		(4 "In1.Cu" signal "GND")
		(6 "In2.Cu" signal "IN1")
		(8 "In3.Cu" signal "GND1")
		(10 "In4.Cu" signal "IN2")
		(12 "In5.Cu" signal "GND2")
		(14 "In6.Cu" signal "IN3")
		(16 "In7.Cu" signal "GND3")
		(18 "In8.Cu" signal "VCC")
		(20 "In9.Cu" signal "VCC1")
		(22 "In10.Cu" signal "GND4")
		(24 "In11.Cu" signal "IN4")
		(26 "In12.Cu" signal "GND5")
		(28 "In13.Cu" signal "IN5")
		(30 "In14.Cu" signal "GND6")
		(32 "In15.Cu" signal "IN6")
		(34 "In16.Cu" signal "GND7")
		(2 "B.Cu" signal "BOTTOM")
		(9 "F.Adhes" user "F.Adhesive")
		(11 "B.Adhes" user "B.Adhesive")
		(13 "F.Paste" user "Package Geometry/Pastemask Top")
		(15 "B.Paste" user "Package Geometry/Pastemask Bottom")
		(5 "F.SilkS" user "Ref Des/Silkscreen Top")
		(7 "B.SilkS" user "Ref Des/Silkscreen Bottom")
		(1 "F.Mask" user "Board Geometry/Soldermask Top")
		(3 "B.Mask" user "Board Geometry/Soldermask Bottom")
		(17 "Dwgs.User" user "User.Drawings")
		(19 "Cmts.User" user "User.Comments")
		(21 "Eco1.User" user "User.Eco1")
		(23 "Eco2.User" user "User.Eco2")
		(25 "Edge.Cuts" user "Board Geometry/Outline")
		(27 "Margin" user)
		(31 "F.CrtYd" user "Package Geometry/Place Bound Top")
		(29 "B.CrtYd" user "Package Geometry/Place Bound Bottom")
		(35 "F.Fab" user "Ref Des/Assembly Top")
		(33 "B.Fab" user "Ref Des/Assembly Bottom")
	)
	(footprint ""
		(layer "B.Cu")
		(at 44.14901 -412.853378)
		(property "Reference" "C2074"
			(at 0 0 0)
			(layer "B.SilkS")
			(hide yes)
			(effects
				(font
					(size 1.27 1.27)
				)
				(justify mirror)
			)
		)
		(property "Value" ""
			(at 0 0 0)
			(layer "B.Fab")
			(effects
				(font
					(size 1.27 1.27)
				)
				(justify mirror)
			)
		)
		(duplicate_pad_numbers_are_jumpers no)
		(fp_line
			(start -0.299974 -0.150114)
			(end -0.299974 0.150114)
			(stroke
				(width 0.1)
				(type default)
			)
			(layer "B.Fab")
		)
		(fp_line
			(start -0.299974 0.150114)
			(end 0.299974 0.150114)
			(stroke
				(width 0.1)
				(type default)
			)
			(layer "B.Fab")
		)
		(fp_line
			(start 0.299974 -0.150114)
			(end -0.299974 -0.150114)
			(stroke
				(width 0.1)
				(type default)
			)
			(layer "B.Fab")
		)
		(fp_line
			(start 0.299974 0.150114)
			(end 0.299974 -0.150114)
			(stroke
				(width 0.1)
				(type default)
			)
			(layer "B.Fab")
		)
		(pad "1" smd rect
			(at 0.2667 0 180)
			(size 0.3048 0.381)
			(layers "B.Cu" "B.Mask" "B.Paste")
			(net "P3E_CPU1_P5_TX_C_DN<1>")
		)
		(pad "2" smd rect
			(at -0.2667 0 180)
			(size 0.3048 0.381)
			(layers "B.Cu" "B.Mask" "B.Paste")
			(net "P3E_CPU1_P5_TX_DN<1>")
		)
	)
	(footprint ""
		(layer "B.Cu")
		(at 350.199198 -252.224032 60)
		(property "Reference" "C2567"
			(at 0 0 60)
			(layer "B.SilkS")
			(hide yes)
			(effects
				(font
					(size 1.27 1.27)
				)
				(justify mirror)
			)
		)
		(property "Value" ""
			(at 0 0 60)
			(layer "B.Fab")
			(effects
				(font
					(size 1.27 1.27)
				)
				(justify mirror)
			)
		)
		(duplicate_pad_numbers_are_jumpers no)
		(fp_line
			(start -0.787516 -0.406438)
			(end -0.787425 0.40652)
			(stroke
				(width 0.1524)
				(type default)
			)
			(layer "B.SilkS")
		)
		(fp_line
			(start -0.787425 0.40652)
			(end 0.787516 0.406438)
			(stroke
				(width 0.1524)
				(type default)
			)
			(layer "B.SilkS")
		)
		(fp_line
			(start 0.787425 -0.40652)
			(end -0.787516 -0.406438)
			(stroke
				(width 0.1524)
				(type default)
			)
			(layer "B.SilkS")
		)
		(fp_line
			(start 0.787516 0.406438)
			(end 0.787425 -0.40652)
			(stroke
				(width 0.1524)
				(type default)
			)
			(layer "B.SilkS")
		)
		(fp_line
			(start -0.679568 -0.304811)
			(end -0.6795 0.304908)
			(stroke
				(width 0.1)
				(type default)
			)
			(layer "B.Fab")
		)
		(fp_line
			(start -0.120605 -0.304905)
			(end -0.679568 -0.304811)
			(stroke
				(width 0.1)
				(type default)
			)
			(layer "B.Fab")
		)
		(fp_line
			(start -0.120554 -0.279418)
			(end -0.120605 -0.304905)
			(stroke
				(width 0.1)
				(type default)
			)
			(layer "B.Fab")
		)
		(fp_line
			(start 0.120629 -0.30516)
			(end 0.120587 -0.279326)
			(stroke
				(width 0.1)
				(type default)
			)
			(layer "B.Fab")
		)
		(fp_line
			(start 0.120587 -0.279326)
			(end -0.120554 -0.279418)
			(stroke
				(width 0.1)
				(type default)
			)
			(layer "B.Fab")
		)
		(fp_line
			(start -0.6795 0.304908)
			(end -0.120316 0.304686)
			(stroke
				(width 0.1)
				(type default)
			)
			(layer "B.Fab")
		)
		(fp_line
			(start 0.679373 -0.305128)
			(end 0.120629 -0.30516)
			(stroke
				(width 0.1)
				(type default)
			)
			(layer "B.Fab")
		)
		(fp_line
			(start -0.12024 0.279419)
			(end 0.120554 0.279418)
			(stroke
				(width 0.1)
				(type default)
			)
			(layer "B.Fab")
		)
		(fp_line
			(start -0.120316 0.304686)
			(end -0.12024 0.279419)
			(stroke
				(width 0.1)
				(type default)
			)
			(layer "B.Fab")
		)
		(fp_line
			(start 0.120554 0.279418)
			(end 0.120605 0.304905)
			(stroke
				(width 0.1)
				(type default)
			)
			(layer "B.Fab")
		)
		(fp_line
			(start 0.120605 0.304905)
			(end 0.679568 0.304811)
			(stroke
				(width 0.1)
				(type default)
			)
			(layer "B.Fab")
		)
		(fp_line
			(start 0.679568 0.304811)
			(end 0.679373 -0.305128)
			(stroke
				(width 0.1)
				(type default)
			)
			(layer "B.Fab")
		)
		(pad "1" smd circle
			(at 0.40005 0 240)
			(size 0 0)
			(layers "B.Cu" "B.Mask" "B.Paste")
			(net "PVDDCR_SOC_P0")
		)
		(pad "2" smd circle
			(at -0.40005 0 240)
			(size 0 0)
			(layers "B.Cu" "B.Mask" "B.Paste")
			(net "GND")
		)
	)
	(footprint ""
		(layer "B.Cu")
		(at 405.809196 -354.439728 -90)
		(property "Reference" "R6125"
			(at 0 0 90)
			(layer "B.SilkS")
			(hide yes)
			(effects
				(font
					(size 1.27 1.27)
				)
				(justify mirror)
			)
		)
		(property "Value" ""
			(at 0 0 90)
			(layer "B.Fab")
			(effects
				(font
					(size 1.27 1.27)
				)
				(justify mirror)
			)
		)
		(duplicate_pad_numbers_are_jumpers no)
		(fp_line
			(start -0.7874 0.4064)
			(end 0.7874 0.4064)
			(stroke
				(width 0.1524)
				(type default)
			)
			(layer "B.SilkS")
		)
		(fp_line
			(start 0.7874 0.4064)
			(end 0.7874 -0.4064)
			(stroke
				(width 0.1524)
				(type default)
			)
			(layer "B.SilkS")
		)
		(fp_line
			(start -0.7874 -0.4064)
			(end -0.7874 0.4064)
			(stroke
				(width 0.1524)
				(type default)
			)
			(layer "B.SilkS")
		)
		(fp_line
			(start 0.7874 -0.4064)
			(end -0.7874 -0.4064)
			(stroke
				(width 0.1524)
				(type default)
			)
			(layer "B.SilkS")
		)
		(fp_line
			(start -0.67945 0.3048)
			(end -0.120396 0.3048)
			(stroke
				(width 0.1)
				(type default)
			)
			(layer "B.Fab")
		)
		(fp_line
			(start -0.120396 0.3048)
			(end -0.120396 0.2794)
			(stroke
				(width 0.1)
				(type default)
			)
			(layer "B.Fab")
		)
		(fp_line
			(start 0.12065 0.3048)
			(end 0.67945 0.3048)
			(stroke
				(width 0.1)
				(type default)
			)
			(layer "B.Fab")
		)
		(fp_line
			(start 0.67945 0.3048)
			(end 0.67945 -0.305054)
			(stroke
				(width 0.1)
				(type default)
			)
			(layer "B.Fab")
		)
		(fp_line
			(start -0.120396 0.2794)
			(end 0.12065 0.2794)
			(stroke
				(width 0.1)
				(type default)
			)
			(layer "B.Fab")
		)
		(fp_line
			(start 0.12065 0.2794)
			(end 0.12065 0.3048)
			(stroke
				(width 0.1)
				(type default)
			)
			(layer "B.Fab")
		)
		(fp_line
			(start -0.12065 -0.2794)
			(end -0.12065 -0.3048)
			(stroke
				(width 0.1)
				(type default)
			)
			(layer "B.Fab")
		)
		(fp_line
			(start 0.12065 -0.2794)
			(end -0.12065 -0.2794)
			(stroke
				(width 0.1)
				(type default)
			)
			(layer "B.Fab")
		)
		(fp_line
			(start -0.67945 -0.3048)
			(end -0.67945 0.3048)
			(stroke
				(width 0.1)
				(type default)
			)
			(layer "B.Fab")
		)
		(fp_line
			(start -0.12065 -0.3048)
			(end -0.67945 -0.3048)
			(stroke
				(width 0.1)
				(type default)
			)
			(layer "B.Fab")
		)
		(fp_line
			(start 0.12065 -0.305054)
			(end 0.12065 -0.2794)
			(stroke
				(width 0.1)
				(type default)
			)
			(layer "B.Fab")
		)
		(fp_line
			(start 0.67945 -0.305054)
			(end 0.12065 -0.305054)
			(stroke
				(width 0.1)
				(type default)
			)
			(layer "B.Fab")
		)
		(pad "1" smd circle
			(at 0.40005 0 90)
			(size 0 0)
			(layers "B.Cu" "B.Mask" "B.Paste")
			(net "FM_BOARD_SKU_ID4")
		)
		(pad "2" smd circle
			(at -0.40005 0 90)
			(size 0 0)
			(layers "B.Cu" "B.Mask" "B.Paste")
			(net "GND")
		)
	)
	(footprint ""
		(layer "B.Cu")
		(at 363.645958 -258.795012 180)
		(property "Reference" "C2558"
			(at 0 0 0)
			(layer "B.SilkS")
			(hide yes)
			(effects
				(font
					(size 1.27 1.27)
				)
				(justify mirror)
			)
		)
		(property "Value" ""
			(at 0 0 0)
			(layer "B.Fab")
			(effects
				(font
					(size 1.27 1.27)
				)
				(justify mirror)
			)
		)
		(duplicate_pad_numbers_are_jumpers no)
		(fp_line
			(start 0.7874 0.4064)
			(end 0.7874 -0.4064)
			(stroke
				(width 0.1524)
				(type default)
			)
			(layer "B.SilkS")
		)
		(fp_line
			(start 0.7874 -0.4064)
			(end -0.7874 -0.4064)
			(stroke
				(width 0.1524)
				(type default)
			)
			(layer "B.SilkS")
		)
		(fp_line
			(start -0.7874 0.4064)
			(end 0.7874 0.4064)
			(stroke
				(width 0.1524)
				(type default)
			)
			(layer "B.SilkS")
		)
		(fp_line
			(start -0.7874 -0.4064)
			(end -0.7874 0.4064)
			(stroke
				(width 0.1524)
				(type default)
			)
			(layer "B.SilkS")
		)
		(fp_line
			(start 0.67945 0.3048)
			(end 0.67945 -0.305054)
			(stroke
				(width 0.1)
				(type default)
			)
			(layer "B.Fab")
		)
		(fp_line
			(start 0.67945 -0.305054)
			(end 0.12065 -0.305054)
			(stroke
				(width 0.1)
				(type default)
			)
			(layer "B.Fab")
		)
		(fp_line
			(start 0.12065 0.3048)
			(end 0.67945 0.3048)
			(stroke
				(width 0.1)
				(type default)
			)
			(layer "B.Fab")
		)
		(fp_line
			(start 0.12065 0.2794)
			(end 0.12065 0.3048)
			(stroke
				(width 0.1)
				(type default)
			)
			(layer "B.Fab")
		)
		(fp_line
			(start 0.12065 -0.2794)
			(end -0.12065 -0.2794)
			(stroke
				(width 0.1)
				(type default)
			)
			(layer "B.Fab")
		)
		(fp_line
			(start 0.12065 -0.305054)
			(end 0.12065 -0.2794)
			(stroke
				(width 0.1)
				(type default)
			)
			(layer "B.Fab")
		)
		(fp_line
			(start -0.120396 0.3048)
			(end -0.120396 0.2794)
			(stroke
				(width 0.1)
				(type default)
			)
			(layer "B.Fab")
		)
		(fp_line
			(start -0.120396 0.2794)
			(end 0.12065 0.2794)
			(stroke
				(width 0.1)
				(type default)
			)
			(layer "B.Fab")
		)
		(fp_line
			(start -0.12065 -0.2794)
			(end -0.12065 -0.3048)
			(stroke
				(width 0.1)
				(type default)
			)
			(layer "B.Fab")
		)
		(fp_line
			(start -0.12065 -0.3048)
			(end -0.67945 -0.3048)
			(stroke
				(width 0.1)
				(type default)
			)
			(layer "B.Fab")
		)
		(fp_line
			(start -0.67945 0.3048)
			(end -0.120396 0.3048)
			(stroke
				(width 0.1)
				(type default)
			)
			(layer "B.Fab")
		)
		(fp_line
			(start -0.67945 -0.3048)
			(end -0.67945 0.3048)
			(stroke
				(width 0.1)
				(type default)
			)
			(layer "B.Fab")
		)
		(pad "1" smd circle
			(at 0.40005 0)
			(size 0 0)
			(layers "B.Cu" "B.Mask" "B.Paste")
			(net "PVDDCR_SOC_P0")
		)
		(pad "2" smd circle
			(at -0.40005 0)
			(size 0 0)
			(layers "B.Cu" "B.Mask" "B.Paste")
			(net "GND")
		)
	)
	(footprint ""
		(layer "B.Cu")
		(at 171.214288 -107.188 180)
		(property "Reference" "R234"
			(at 0 0 0)
			(layer "B.SilkS")
			(hide yes)
			(effects
				(font
					(size 1.27 1.27)
				)
				(justify mirror)
			)
		)
		(property "Value" ""
			(at 0 0 0)
			(layer "B.Fab")
			(effects
				(font
					(size 1.27 1.27)
				)
				(justify mirror)
			)
		)
		(duplicate_pad_numbers_are_jumpers no)
		(fp_line
			(start 0.7874 0.4064)
			(end 0.7874 -0.4064)
			(stroke
				(width 0.1524)
				(type default)
			)
			(layer "B.SilkS")
		)
		(fp_line
			(start 0.7874 -0.4064)
			(end -0.7874 -0.4064)
			(stroke
				(width 0.1524)
				(type default)
			)
			(layer "B.SilkS")
		)
		(fp_line
			(start -0.7874 0.4064)
			(end 0.7874 0.4064)
			(stroke
				(width 0.1524)
				(type default)
			)
			(layer "B.SilkS")
		)
		(fp_line
			(start -0.7874 -0.4064)
			(end -0.7874 0.4064)
			(stroke
				(width 0.1524)
				(type default)
			)
			(layer "B.SilkS")
		)
		(fp_line
			(start 0.67945 0.3048)
			(end 0.67945 -0.305054)
			(stroke
				(width 0.1)
				(type default)
			)
			(layer "B.Fab")
		)
		(fp_line
			(start 0.67945 -0.305054)
			(end 0.12065 -0.305054)
			(stroke
				(width 0.1)
				(type default)
			)
			(layer "B.Fab")
		)
		(fp_line
			(start 0.12065 0.3048)
			(end 0.67945 0.3048)
			(stroke
				(width 0.1)
				(type default)
			)
			(layer "B.Fab")
		)
		(fp_line
			(start 0.12065 0.2794)
			(end 0.12065 0.3048)
			(stroke
				(width 0.1)
				(type default)
			)
			(layer "B.Fab")
		)
		(fp_line
			(start 0.12065 -0.2794)
			(end -0.12065 -0.2794)
			(stroke
				(width 0.1)
				(type default)
			)
			(layer "B.Fab")
		)
		(fp_line
			(start 0.12065 -0.305054)
			(end 0.12065 -0.2794)
			(stroke
				(width 0.1)
				(type default)
			)
			(layer "B.Fab")
		)
		(fp_line
			(start -0.120396 0.3048)
			(end -0.120396 0.2794)
			(stroke
				(width 0.1)
				(type default)
			)
			(layer "B.Fab")
		)
		(fp_line
			(start -0.120396 0.2794)
			(end 0.12065 0.2794)
			(stroke
				(width 0.1)
				(type default)
			)
			(layer "B.Fab")
		)
		(fp_line
			(start -0.12065 -0.2794)
			(end -0.12065 -0.3048)
			(stroke
				(width 0.1)
				(type default)
			)
			(layer "B.Fab")
		)
		(fp_line
			(start -0.12065 -0.3048)
			(end -0.67945 -0.3048)
			(stroke
				(width 0.1)
				(type default)
			)
			(layer "B.Fab")
		)
		(fp_line
			(start -0.67945 0.3048)
			(end -0.120396 0.3048)
			(stroke
				(width 0.1)
				(type default)
			)
			(layer "B.Fab")
		)
		(fp_line
			(start -0.67945 -0.3048)
			(end -0.67945 0.3048)
			(stroke
				(width 0.1)
				(type default)
			)
			(layer "B.Fab")
		)
		(pad "1" smd circle
			(at 0.40005 0)
			(size 0 0)
			(layers "B.Cu" "B.Mask" "B.Paste")
			(net "CPU1_XTRIG_L6")
		)
		(pad "2" smd circle
			(at -0.40005 0)
			(size 0 0)
			(layers "B.Cu" "B.Mask" "B.Paste")
			(net "FM_CPU1_XTRIG_L6")
		)
	)
	(footprint ""
		(layer "B.Cu")
		(at 203.073 -75.053952)
		(property "Reference" "R3210"
			(at 0 0 0)
			(layer "B.SilkS")
			(hide yes)
			(effects
				(font
					(size 1.27 1.27)
				)
				(justify mirror)
			)
		)
		(property "Value" ""
			(at 0 0 0)
			(layer "B.Fab")
			(effects
				(font
					(size 1.27 1.27)
				)
				(justify mirror)
			)
		)
		(duplicate_pad_numbers_are_jumpers no)
		(fp_line
			(start -0.7874 -0.4064)
			(end -0.7874 0.4064)
			(stroke
				(width 0.1524)
				(type default)
			)
			(layer "B.SilkS")
		)
		(fp_line
			(start -0.7874 0.4064)
			(end 0.7874 0.4064)
			(stroke
				(width 0.1524)
				(type default)
			)
			(layer "B.SilkS")
		)
		(fp_line
			(start 0.7874 -0.4064)
			(end -0.7874 -0.4064)
			(stroke
				(width 0.1524)
				(type default)
			)
			(layer "B.SilkS")
		)
		(fp_line
			(start 0.7874 0.4064)
			(end 0.7874 -0.4064)
			(stroke
				(width 0.1524)
				(type default)
			)
			(layer "B.SilkS")
		)
		(fp_line
			(start -0.67945 -0.3048)
			(end -0.67945 0.3048)
			(stroke
				(width 0.1)
				(type default)
			)
			(layer "B.Fab")
		)
		(fp_line
			(start -0.67945 0.3048)
			(end -0.120396 0.3048)
			(stroke
				(width 0.1)
				(type default)
			)
			(layer "B.Fab")
		)
		(fp_line
			(start -0.12065 -0.3048)
			(end -0.67945 -0.3048)
			(stroke
				(width 0.1)
				(type default)
			)
			(layer "B.Fab")
		)
		(fp_line
			(start -0.12065 -0.2794)
			(end -0.12065 -0.3048)
			(stroke
				(width 0.1)
				(type default)
			)
			(layer "B.Fab")
		)
		(fp_line
			(start -0.120396 0.2794)
			(end 0.12065 0.2794)
			(stroke
				(width 0.1)
				(type default)
			)
			(layer "B.Fab")
		)
		(fp_line
			(start -0.120396 0.3048)
			(end -0.120396 0.2794)
			(stroke
				(width 0.1)
				(type default)
			)
			(layer "B.Fab")
		)
		(fp_line
			(start 0.12065 -0.305054)
			(end 0.12065 -0.2794)
			(stroke
				(width 0.1)
				(type default)
			)
			(layer "B.Fab")
		)
		(fp_line
			(start 0.12065 -0.2794)
			(end -0.12065 -0.2794)
			(stroke
				(width 0.1)
				(type default)
			)
			(layer "B.Fab")
		)
		(fp_line
			(start 0.12065 0.2794)
			(end 0.12065 0.3048)
			(stroke
				(width 0.1)
				(type default)
			)
			(layer "B.Fab")
		)
		(fp_line
			(start 0.12065 0.3048)
			(end 0.67945 0.3048)
			(stroke
				(width 0.1)
				(type default)
			)
			(layer "B.Fab")
		)
		(fp_line
			(start 0.67945 -0.305054)
			(end 0.12065 -0.305054)
			(stroke
				(width 0.1)
				(type default)
			)
			(layer "B.Fab")
		)
		(fp_line
			(start 0.67945 0.3048)
			(end 0.67945 -0.305054)
			(stroke
				(width 0.1)
				(type default)
			)
			(layer "B.Fab")
		)
		(pad "1" smd circle
			(at 0.40005 0 180)
			(size 0 0)
			(layers "B.Cu" "B.Mask" "B.Paste")
			(net "NCSI_BMC_CRS_DV_R1")
		)
		(pad "2" smd circle
			(at -0.40005 0 180)
			(size 0 0)
			(layers "B.Cu" "B.Mask" "B.Paste")
			(net "RMII_OCP_BMC_CRSDV")
		)
	)
	(footprint ""
		(layer "B.Cu")
		(at 316.507876 -66.708782 90)
		(property "Reference" "R3100"
			(at 0 0 90)
			(layer "B.SilkS")
			(hide yes)
			(effects
				(font
					(size 1.27 1.27)
				)
				(justify mirror)
			)
		)
		(property "Value" ""
			(at 0 0 90)
			(layer "B.Fab")
			(effects
				(font
					(size 1.27 1.27)
				)
				(justify mirror)
			)
		)
		(duplicate_pad_numbers_are_jumpers no)
		(fp_line
			(start 0.7874 -0.4064)
			(end -0.7874 -0.4064)
			(stroke
				(width 0.1524)
				(type default)
			)
			(layer "B.SilkS")
		)
		(fp_line
			(start -0.7874 -0.4064)
			(end -0.7874 0.4064)
			(stroke
				(width 0.1524)
				(type default)
			)
			(layer "B.SilkS")
		)
		(fp_line
			(start 0.7874 0.4064)
			(end 0.7874 -0.4064)
			(stroke
				(width 0.1524)
				(type default)
			)
			(layer "B.SilkS")
		)
		(fp_line
			(start -0.7874 0.4064)
			(end 0.7874 0.4064)
			(stroke
				(width 0.1524)
				(type default)
			)
			(layer "B.SilkS")
		)
		(fp_line
			(start 0.67945 -0.305054)
			(end 0.12065 -0.305054)
			(stroke
				(width 0.1)
				(type default)
			)
			(layer "B.Fab")
		)
		(fp_line
			(start 0.12065 -0.305054)
			(end 0.12065 -0.2794)
			(stroke
				(width 0.1)
				(type default)
			)
			(layer "B.Fab")
		)
		(fp_line
			(start -0.12065 -0.3048)
			(end -0.67945 -0.3048)
			(stroke
				(width 0.1)
				(type default)
			)
			(layer "B.Fab")
		)
		(fp_line
			(start -0.67945 -0.3048)
			(end -0.67945 0.3048)
			(stroke
				(width 0.1)
				(type default)
			)
			(layer "B.Fab")
		)
		(fp_line
			(start 0.12065 -0.2794)
			(end -0.12065 -0.2794)
			(stroke
				(width 0.1)
				(type default)
			)
			(layer "B.Fab")
		)
		(fp_line
			(start -0.12065 -0.2794)
			(end -0.12065 -0.3048)
			(stroke
				(width 0.1)
				(type default)
			)
			(layer "B.Fab")
		)
		(fp_line
			(start 0.12065 0.2794)
			(end 0.12065 0.3048)
			(stroke
				(width 0.1)
				(type default)
			)
			(layer "B.Fab")
		)
		(fp_line
			(start -0.120396 0.2794)
			(end 0.12065 0.2794)
			(stroke
				(width 0.1)
				(type default)
			)
			(layer "B.Fab")
		)
		(fp_line
			(start 0.67945 0.3048)
			(end 0.67945 -0.305054)
			(stroke
				(width 0.1)
				(type default)
			)
			(layer "B.Fab")
		)
		(fp_line
			(start 0.12065 0.3048)
			(end 0.67945 0.3048)
			(stroke
				(width 0.1)
				(type default)
			)
			(layer "B.Fab")
		)
		(fp_line
			(start -0.120396 0.3048)
			(end -0.120396 0.2794)
			(stroke
				(width 0.1)
				(type default)
			)
			(layer "B.Fab")
		)
		(fp_line
			(start -0.67945 0.3048)
			(end -0.120396 0.3048)
			(stroke
				(width 0.1)
				(type default)
			)
			(layer "B.Fab")
		)
		(pad "1" smd circle
			(at 0.40005 0 270)
			(size 0 0)
			(layers "B.Cu" "B.Mask" "B.Paste")
			(net "LED_P3V3")
		)
		(pad "2" smd circle
			(at -0.40005 0 270)
			(size 0 0)
			(layers "B.Cu" "B.Mask" "B.Paste")
			(net "P3V3")
		)
	)
)
